# T6G (Grand Teton) — schematic netlist excerpt (pin names and nets, part order shuffled) for the footprints in the layout excerpt that follows; sources: Cadence DE-HDL packaged netlist, KiCad conversion of 04192023_DAF0TMB3IC0_F0TG_MB_C_brd_V02_OCP.brd

R6804  Q_RES  0 5% CHIP  pkg 0402LF  page 81 : A = RST_RT_CPU0_P0_PERST_R_N ; B = RST_RT_CPU0_P0_PERST_R2_N
R677  Q_RES  49.9 1% CHIP  pkg 0201LF  page 287 : A = SMB_RT_CPU0_P1_ROM_MUX_1D_SDA ; B = SMB_RT_CPU0_P1_ROM_MUX_1D_R_SDA
R2948  Q_RES  4.7K 5% EMPTY  pkg 0402LF  page 241 : A = FM_GPU_HSC_EN_BUF_R ; B = GND

(kicad_pcb
	(version 20260206)
	(generator "pcbnew")
	(generator_version "10.0")
	(general
		(thickness 1.6)
		(legacy_teardrops no)
	)
	(paper "A4")
	(title_block
		(title "04192023_DAF0TMB3IC0_F0TG_MB_C_brd_V02_OCP.brd")
		(comment 1 "Grand Teton / footprints 1110-1112 of 8354")
	)
	(layers
		(0 "F.Cu" signal "TOP")
		(4 "In1.Cu" signal "GND")
		(6 "In2.Cu" signal "IN1")
		(8 "In3.Cu" signal "GND1")
		(10 "In4.Cu" signal "IN2")
		(12 "In5.Cu" signal "GND2")
		(14 "In6.Cu" signal "IN3")
		(16 "In7.Cu" signal "GND3")
		(18 "In8.Cu" signal "VCC")
		(20 "In9.Cu" signal "VCC1")
		(22 "In10.Cu" signal "GND4")
		(24 "In11.Cu" signal "IN4")
		(26 "In12.Cu" signal "GND5")
		(28 "In13.Cu" signal "IN5")
		(30 "In14.Cu" signal "GND6")
		(32 "In15.Cu" signal "IN6")
		(34 "In16.Cu" signal "GND7")
		(2 "B.Cu" signal "BOTTOM")
		(9 "F.Adhes" user "F.Adhesive")
		(11 "B.Adhes" user "B.Adhesive")
		(13 "F.Paste" user "Package Geometry/Pastemask Top")
		(15 "B.Paste" user "Package Geometry/Pastemask Bottom")
		(5 "F.SilkS" user "Ref Des/Silkscreen Top")
		(7 "B.SilkS" user "Ref Des/Silkscreen Bottom")
		(1 "F.Mask" user "Board Geometry/Soldermask Top")
		(3 "B.Mask" user "Board Geometry/Soldermask Bottom")
		(17 "Dwgs.User" user "User.Drawings")
		(19 "Cmts.User" user "User.Comments")
		(21 "Eco1.User" user "User.Eco1")
		(23 "Eco2.User" user "User.Eco2")
		(25 "Edge.Cuts" user "Board Geometry/Outline")
		(27 "Margin" user)
		(31 "F.CrtYd" user "Package Geometry/Place Bound Top")
		(29 "B.CrtYd" user "Package Geometry/Place Bound Bottom")
		(35 "F.Fab" user "Ref Des/Assembly Top")
		(33 "B.Fab" user "Ref Des/Assembly Bottom")
	)
	(footprint ""
		(layer "F.Cu")
		(at 171.174664 -120.464072)
		(property "Reference" "R6804"
			(at 0 0 0)
			(layer "F.SilkS")
			(hide yes)
			(effects
				(font
					(size 1.27 1.27)
				)
			)
		)
		(property "Value" ""
			(at 0 0 0)
			(layer "F.Fab")
			(effects
				(font
					(size 1.27 1.27)
				)
			)
		)
		(duplicate_pad_numbers_are_jumpers no)
		(fp_line
			(start -0.7874 -0.4064)
			(end 0.7874 -0.4064)
			(stroke
				(width 0.1524)
				(type default)
			)
			(layer "F.SilkS")
		)
		(fp_line
			(start -0.7874 0.4064)
			(end -0.7874 -0.4064)
			(stroke
				(width 0.1524)
				(type default)
			)
			(layer "F.SilkS")
		)
		(fp_line
			(start 0.7874 -0.4064)
			(end 0.7874 0.4064)
			(stroke
				(width 0.1524)
				(type default)
			)
			(layer "F.SilkS")
		)
		(fp_line
			(start 0.7874 0.4064)
			(end -0.7874 0.4064)
			(stroke
				(width 0.1524)
				(type default)
			)
			(layer "F.SilkS")
		)
		(fp_line
			(start -0.67945 -0.305054)
			(end -0.12065 -0.305054)
			(stroke
				(width 0.1)
				(type default)
			)
			(layer "F.Fab")
		)
		(fp_line
			(start -0.67945 0.3048)
			(end -0.67945 -0.305054)
			(stroke
				(width 0.1)
				(type default)
			)
			(layer "F.Fab")
		)
		(fp_line
			(start -0.12065 -0.305054)
			(end -0.12065 -0.2794)
			(stroke
				(width 0.1)
				(type default)
			)
			(layer "F.Fab")
		)
		(fp_line
			(start -0.12065 -0.2794)
			(end 0.12065 -0.2794)
			(stroke
				(width 0.1)
				(type default)
			)
			(layer "F.Fab")
		)
		(fp_line
			(start -0.12065 0.2794)
			(end -0.12065 0.3048)
			(stroke
				(width 0.1)
				(type default)
			)
			(layer "F.Fab")
		)
		(fp_line
			(start -0.12065 0.3048)
			(end -0.67945 0.3048)
			(stroke
				(width 0.1)
				(type default)
			)
			(layer "F.Fab")
		)
		(fp_line
			(start 0.120396 0.2794)
			(end -0.12065 0.2794)
			(stroke
				(width 0.1)
				(type default)
			)
			(layer "F.Fab")
		)
		(fp_line
			(start 0.120396 0.3048)
			(end 0.120396 0.2794)
			(stroke
				(width 0.1)
				(type default)
			)
			(layer "F.Fab")
		)
		(fp_line
			(start 0.12065 -0.3048)
			(end 0.67945 -0.3048)
			(stroke
				(width 0.1)
				(type default)
			)
			(layer "F.Fab")
		)
		(fp_line
			(start 0.12065 -0.2794)
			(end 0.12065 -0.3048)
			(stroke
				(width 0.1)
				(type default)
			)
			(layer "F.Fab")
		)
		(fp_line
			(start 0.67945 -0.3048)
			(end 0.67945 0.3048)
			(stroke
				(width 0.1)
				(type default)
			)
			(layer "F.Fab")
		)
		(fp_line
			(start 0.67945 0.3048)
			(end 0.120396 0.3048)
			(stroke
				(width 0.1)
				(type default)
			)
			(layer "F.Fab")
		)
		(pad "1" smd circle
			(at -0.40005 0)
			(size 0 0)
			(layers "F.Cu" "F.Mask" "F.Paste")
			(net "RST_RT_CPU0_P0_PERST_R_N")
		)
		(pad "2" smd circle
			(at 0.40005 0)
			(size 0 0)
			(layers "F.Cu" "F.Mask" "F.Paste")
			(net "RST_RT_CPU0_P0_PERST_R2_N")
		)
	)
	(footprint ""
		(layer "F.Cu")
		(at 330.932536 -388.149338)
		(property "Reference" "R677"
			(at 0 0 0)
			(layer "F.SilkS")
			(hide yes)
			(effects
				(font
					(size 1.27 1.27)
				)
			)
		)
		(property "Value" ""
			(at 0 0 0)
			(layer "F.Fab")
			(effects
				(font
					(size 1.27 1.27)
				)
			)
		)
		(duplicate_pad_numbers_are_jumpers no)
		(fp_line
			(start -0.32512 -0.175006)
			(end 0.32512 -0.175006)
			(stroke
				(width 0.1)
				(type default)
			)
			(layer "F.Fab")
		)
		(fp_line
			(start -0.32512 0.175006)
			(end -0.32512 -0.175006)
			(stroke
				(width 0.1)
				(type default)
			)
			(layer "F.Fab")
		)
		(fp_line
			(start 0.32512 -0.175006)
			(end 0.32512 0.175006)
			(stroke
				(width 0.1)
				(type default)
			)
			(layer "F.Fab")
		)
		(fp_line
			(start 0.32512 0.175006)
			(end -0.32512 0.175006)
			(stroke
				(width 0.1)
				(type default)
			)
			(layer "F.Fab")
		)
		(pad "1" smd rect
			(at -0.2667 0)
			(size 0.3048 0.381)
			(layers "F.Cu" "F.Mask" "F.Paste")
			(net "SMB_RT_CPU0_P1_ROM_MUX_1D_SDA")
		)
		(pad "2" smd rect
			(at 0.2667 0 180)
			(size 0.3048 0.381)
			(layers "F.Cu" "F.Mask" "F.Paste")
			(net "SMB_RT_CPU0_P1_ROM_MUX_1D_R_SDA")
		)
	)
	(footprint ""
		(layer "F.Cu")
		(at 193.55562 -422.804082 90)
		(property "Reference" "R2948"
			(at 0 0 90)
			(layer "F.SilkS")
			(hide yes)
			(effects
				(font
					(size 1.27 1.27)
				)
			)
		)
		(property "Value" ""
			(at 0 0 90)
			(layer "F.Fab")
			(effects
				(font
					(size 1.27 1.27)
				)
			)
		)
		(duplicate_pad_numbers_are_jumpers no)
		(fp_line
			(start 0.7874 -0.4064)
			(end 0.7874 0.4064)
			(stroke
				(width 0.1524)
				(type default)
			)
			(layer "F.SilkS")
		)
		(fp_line
			(start -0.7874 -0.4064)
			(end 0.7874 -0.4064)
			(stroke
				(width 0.1524)
				(type default)
			)
			(layer "F.SilkS")
		)
		(fp_line
			(start 0.7874 0.4064)
			(end -0.7874 0.4064)
			(stroke
				(width 0.1524)
				(type default)
			)
			(layer "F.SilkS")
		)
		(fp_line
			(start -0.7874 0.4064)
			(end -0.7874 -0.4064)
			(stroke
				(width 0.1524)
				(type default)
			)
			(layer "F.SilkS")
		)
		(fp_line
			(start -0.12065 -0.305054)
			(end -0.12065 -0.2794)
			(stroke
				(width 0.1)
				(type default)
			)
			(layer "F.Fab")
		)
		(fp_line
			(start -0.67945 -0.305054)
			(end -0.12065 -0.305054)
			(stroke
				(width 0.1)
				(type default)
			)
			(layer "F.Fab")
		)
		(fp_line
			(start 0.67945 -0.3048)
			(end 0.67945 0.3048)
			(stroke
				(width 0.1)
				(type default)
			)
			(layer "F.Fab")
		)
		(fp_line
			(start 0.12065 -0.3048)
			(end 0.67945 -0.3048)
			(stroke
				(width 0.1)
				(type default)
			)
			(layer "F.Fab")
		)
		(fp_line
			(start 0.12065 -0.2794)
			(end 0.12065 -0.3048)
			(stroke
				(width 0.1)
				(type default)
			)
			(layer "F.Fab")
		)
		(fp_line
			(start -0.12065 -0.2794)
			(end 0.12065 -0.2794)
			(stroke
				(width 0.1)
				(type default)
			)
			(layer "F.Fab")
		)
		(fp_line
			(start 0.120396 0.2794)
			(end -0.12065 0.2794)
			(stroke
				(width 0.1)
				(type default)
			)
			(layer "F.Fab")
		)
		(fp_line
			(start -0.12065 0.2794)
			(end -0.12065 0.3048)
			(stroke
				(width 0.1)
				(type default)
			)
			(layer "F.Fab")
		)
		(fp_line
			(start 0.67945 0.3048)
			(end 0.120396 0.3048)
			(stroke
				(width 0.1)
				(type default)
			)
			(layer "F.Fab")
		)
		(fp_line
			(start 0.120396 0.3048)
			(end 0.120396 0.2794)
			(stroke
				(width 0.1)
				(type default)
			)
			(layer "F.Fab")
		)
		(fp_line
			(start -0.12065 0.3048)
			(end -0.67945 0.3048)
			(stroke
				(width 0.1)
				(type default)
			)
			(layer "F.Fab")
		)
		(fp_line
			(start -0.67945 0.3048)
			(end -0.67945 -0.305054)
			(stroke
				(width 0.1)
				(type default)
			)
			(layer "F.Fab")
		)
		(pad "1" smd circle
			(at -0.40005 0 90)
			(size 0 0)
			(layers "F.Cu" "F.Mask" "F.Paste")
			(net "FM_GPU_HSC_EN_BUF_R")
		)
		(pad "2" smd circle
			(at 0.40005 0 90)
			(size 0 0)
			(layers "F.Cu" "F.Mask" "F.Paste")
			(net "GND")
		)
	)
)
